(kicad_pcb
	(version 20260206)
	(generator "pcbnew")
	(generator_version "10.0")
	(general
		(thickness 1.6)
		(legacy_teardrops no)
	)
	(paper "A4")
	(title_block
		(title "netronome-mezz — pcbd0082-001_rev01_jul9_a.brd")
		(comment 1 "Open CloudServer (Microsoft) / footprint 225 of 714 (U1), pads 696-811 of 1022")
	)
	(layers
		(0 "F.Cu" signal "TOP")
		(4 "In1.Cu" signal "02_GND")
		(6 "In2.Cu" signal "03_SIG")
		(8 "In3.Cu" signal "04_SIG")
		(10 "In4.Cu" signal "05_GND")
		(12 "In5.Cu" signal "06_PWR1")
		(14 "In6.Cu" signal "07_SIG")
		(16 "In7.Cu" signal "08_SIG")
		(18 "In8.Cu" signal "09_GND")
		(2 "B.Cu" signal "BOTTOM")
		(9 "F.Adhes" user "F.Adhesive")
		(11 "B.Adhes" user "B.Adhesive")
		(13 "F.Paste" user "Package Geometry/Pastemask Top")
		(15 "B.Paste" user "Package Geometry/Pastemask Bottom")
		(5 "F.SilkS" user "Ref Des/Silkscreen Top")
		(7 "B.SilkS" user "Ref Des/Silkscreen Bottom")
		(1 "F.Mask" user "Board Geometry/Soldermask Top")
		(3 "B.Mask" user "Board Geometry/Soldermask Bottom")
		(17 "Dwgs.User" user "User.Drawings")
		(19 "Cmts.User" user "User.Comments")
		(21 "Eco1.User" user "User.Eco1")
		(23 "Eco2.User" user "User.Eco2")
		(25 "Edge.Cuts" user "Board Geometry/Outline")
		(27 "Margin" user)
		(31 "F.CrtYd" user "Package Geometry/Place Bound Top")
		(29 "B.CrtYd" user "Package Geometry/Place Bound Bottom")
		(35 "F.Fab" user "Ref Des/Assembly Top")
		(33 "B.Fab" user "Ref Des/Assembly Bottom")
		(45 "User.4" user "COMPVAL_TYPE_BOTTOM")
	)
	(footprint ""
		(layer "F.Cu")
		(at 54.737 18.542 180)
		(property "Reference" "U1"
			(at -12.192 17.9705 0)
			(unlocked yes)
			(layer "F.SilkS")
			(effects
				(font
					(size 1.27 0.9652)
					(thickness 0.1524)
				)
				(justify left)
			)
		)
		(property "Value" "*"
			(at -0.4826 1.74879 180)
			(unlocked yes)
			(layer "F.Fab")
			(hide yes)
			(effects
				(font
					(size 1.27 0.9652)
					(thickness 0.000001)
				)
				(justify left)
			)
		)
		(property "Device Type" "ICBG0048"
			(at -0.4826 1.74879 180)
			(unlocked yes)
			(layer "F.Fab")
			(hide yes)
			(effects
				(font
					(size 1.27 0.9652)
					(thickness 0.000001)
				)
				(justify left)
			)
		)
		(duplicate_pad_numbers_are_jumpers no)
		(pad "K26" smd circle
			(at 9.500006 -6.500012 180)
			(size 0.508 0.508)
			(layers "F.Cu" "F.Mask" "F.Paste")
			(net "VDD_CORE")
		)
		(pad "K27" smd circle
			(at 10.500004 -6.500012 180)
			(size 0.508 0.508)
			(layers "F.Cu" "F.Mask" "F.Paste")
			(net "VDDA_PLL")
		)
		(pad "K28" smd circle
			(at 11.500002 -6.500012 180)
			(size 0.508 0.508)
			(layers "F.Cu" "F.Mask" "F.Paste")
			(net "_NC_NFP_TS_DFTANATP_AQ0")
		)
		(pad "K29" smd circle
			(at 12.5 -6.500012 180)
			(size 0.508 0.508)
			(layers "F.Cu" "F.Mask" "F.Paste")
			(net "_NC_NFP_TD_TDC")
		)
		(pad "K30" smd circle
			(at 13.499998 -6.500012 180)
			(size 0.508 0.508)
			(layers "F.Cu" "F.Mask" "F.Paste")
			(net "_NC_NFP_TD_TDA")
		)
		(pad "K31" smd circle
			(at 14.499996 -6.500012 180)
			(size 0.508 0.508)
			(layers "F.Cu" "F.Mask" "F.Paste")
			(net "GND")
		)
		(pad "K32" smd circle
			(at 15.499994 -6.500012 180)
			(size 0.508 0.508)
			(layers "F.Cu" "F.Mask" "F.Paste")
			(net "_NC_NFP_TS_TDC")
		)
		(pad "L1" smd circle
			(at -15.499994 -5.499989 180)
			(size 0.508 0.508)
			(layers "F.Cu" "F.Mask" "F.Paste")
			(net "_NC_DDR0_32B_DM1")
		)
		(pad "L2" smd circle
			(at -14.499996 -5.499989 180)
			(size 0.508 0.508)
			(layers "F.Cu" "F.Mask" "F.Paste")
			(net "_NC_DDR0_32B_DQS1_P")
		)
		(pad "L3" smd circle
			(at -13.499998 -5.499989 180)
			(size 0.508 0.508)
			(layers "F.Cu" "F.Mask" "F.Paste")
			(net "_NC_DDR0_32B_DQS1_N")
		)
		(pad "L4" smd circle
			(at -12.5 -5.499989 180)
			(size 0.508 0.508)
			(layers "F.Cu" "F.Mask" "F.Paste")
			(net "_NC_DDR0_32B_DQ10")
		)
		(pad "L5" smd circle
			(at -11.500002 -5.499989 180)
			(size 0.508 0.508)
			(layers "F.Cu" "F.Mask" "F.Paste")
			(net "_NC_DDR0_32B_DQ13")
		)
		(pad "L6" smd circle
			(at -10.500004 -5.499989 180)
			(size 0.508 0.508)
			(layers "F.Cu" "F.Mask" "F.Paste")
			(net "_NC_DDR0_32B_WE_L")
		)
		(pad "L7" smd circle
			(at -9.500006 -5.499989 180)
			(size 0.508 0.508)
			(layers "F.Cu" "F.Mask" "F.Paste")
			(net "_NC_DDR0_32B_A11")
		)
		(pad "L8" smd circle
			(at -8.500008 -5.499989 180)
			(size 0.508 0.508)
			(layers "F.Cu" "F.Mask" "F.Paste")
			(net "_NC_DDR0_32B_A8")
		)
		(pad "L9" smd circle
			(at -7.50001 -5.499989 180)
			(size 0.508 0.508)
			(layers "F.Cu" "F.Mask" "F.Paste")
			(net "_NC_DDR0_32B_ODT0")
		)
		(pad "L10" smd circle
			(at -6.500012 -5.499989 180)
			(size 0.508 0.508)
			(layers "F.Cu" "F.Mask" "F.Paste")
			(net "_NC_B_AZQ")
		)
		(pad "L11" smd circle
			(at -5.499989 -5.499989 180)
			(size 0.508 0.508)
			(layers "F.Cu" "F.Mask" "F.Paste")
			(net "VDD_CORE")
		)
		(pad "L12" smd circle
			(at -4.499991 -5.499989 180)
			(size 0.508 0.508)
			(layers "F.Cu" "F.Mask" "F.Paste")
			(net "GND")
		)
		(pad "L13" smd circle
			(at -3.499993 -5.499989 180)
			(size 0.508 0.508)
			(layers "F.Cu" "F.Mask" "F.Paste")
			(net "VDD_CORE")
		)
		(pad "L14" smd circle
			(at -2.499995 -5.499989 180)
			(size 0.508 0.508)
			(layers "F.Cu" "F.Mask" "F.Paste")
			(net "GND")
		)
		(pad "L15" smd circle
			(at -1.499997 -5.499989 180)
			(size 0.508 0.508)
			(layers "F.Cu" "F.Mask" "F.Paste")
			(net "VDD_CORE")
		)
		(pad "L16" smd circle
			(at -0.499999 -5.499989 180)
			(size 0.508 0.508)
			(layers "F.Cu" "F.Mask" "F.Paste")
			(net "GND")
		)
		(pad "L17" smd circle
			(at 0.499999 -5.499989 180)
			(size 0.508 0.508)
			(layers "F.Cu" "F.Mask" "F.Paste")
			(net "VDD_CORE")
		)
		(pad "L18" smd circle
			(at 1.499997 -5.499989 180)
			(size 0.508 0.508)
			(layers "F.Cu" "F.Mask" "F.Paste")
			(net "GND")
		)
		(pad "L19" smd circle
			(at 2.499995 -5.499989 180)
			(size 0.508 0.508)
			(layers "F.Cu" "F.Mask" "F.Paste")
			(net "VDD_CORE")
		)
		(pad "L20" smd circle
			(at 3.499993 -5.499989 180)
			(size 0.508 0.508)
			(layers "F.Cu" "F.Mask" "F.Paste")
			(net "GND")
		)
		(pad "L21" smd circle
			(at 4.499991 -5.499989 180)
			(size 0.508 0.508)
			(layers "F.Cu" "F.Mask" "F.Paste")
			(net "VDD_CORE")
		)
		(pad "L22" smd circle
			(at 5.499989 -5.499989 180)
			(size 0.508 0.508)
			(layers "F.Cu" "F.Mask" "F.Paste")
			(net "GND")
		)
		(pad "L23" smd circle
			(at 6.500012 -5.499989 180)
			(size 0.508 0.508)
			(layers "F.Cu" "F.Mask" "F.Paste")
			(net "VDD_CORE")
		)
		(pad "L24" smd circle
			(at 7.50001 -5.499989 180)
			(size 0.508 0.508)
			(layers "F.Cu" "F.Mask" "F.Paste")
			(net "GND")
		)
		(pad "L25" smd circle
			(at 8.500008 -5.499989 180)
			(size 0.508 0.508)
			(layers "F.Cu" "F.Mask" "F.Paste")
			(net "VDD_CORE")
		)
		(pad "L26" smd circle
			(at 9.500006 -5.499989 180)
			(size 0.508 0.508)
			(layers "F.Cu" "F.Mask" "F.Paste")
			(net "GND")
		)
		(pad "L27" smd circle
			(at 10.500004 -5.499989 180)
			(size 0.508 0.508)
			(layers "F.Cu" "F.Mask" "F.Paste")
			(net "GND")
		)
		(pad "L28" smd circle
			(at 11.500002 -5.499989 180)
			(size 0.508 0.508)
			(layers "F.Cu" "F.Mask" "F.Paste")
			(net "_NC_NFP_TS_DFTANATP_AQ1")
		)
		(pad "L29" smd circle
			(at 12.5 -5.499989 180)
			(size 0.508 0.508)
			(layers "F.Cu" "F.Mask" "F.Paste")
			(net "VDD_CORE")
		)
		(pad "L30" smd circle
			(at 13.499998 -5.499989 180)
			(size 0.508 0.508)
			(layers "F.Cu" "F.Mask" "F.Paste")
			(net "VDD_CORE")
		)
		(pad "L31" smd circle
			(at 14.499996 -5.499989 180)
			(size 0.508 0.508)
			(layers "F.Cu" "F.Mask" "F.Paste")
			(net "VDD_CORE")
		)
		(pad "L32" smd circle
			(at 15.499994 -5.499989 180)
			(size 0.508 0.508)
			(layers "F.Cu" "F.Mask" "F.Paste")
			(net "_NC_NFP_TS_TDA")
		)
		(pad "M1" smd circle
			(at -15.499994 -4.499991 180)
			(size 0.508 0.508)
			(layers "F.Cu" "F.Mask" "F.Paste")
			(net "_NC_DDR0_32B_DQ11")
		)
		(pad "M2" smd circle
			(at -14.499996 -4.499991 180)
			(size 0.508 0.508)
			(layers "F.Cu" "F.Mask" "F.Paste")
			(net "_NC_DDR0_32B_DQ12")
		)
		(pad "M3" smd circle
			(at -13.499998 -4.499991 180)
			(size 0.508 0.508)
			(layers "F.Cu" "F.Mask" "F.Paste")
			(net "_NC_DDR0_32B_DQ9")
		)
		(pad "M4" smd circle
			(at -12.5 -4.499991 180)
			(size 0.508 0.508)
			(layers "F.Cu" "F.Mask" "F.Paste")
			(net "_NC_DDR0_32B_DQ15")
		)
		(pad "M5" smd circle
			(at -11.500002 -4.499991 180)
			(size 0.508 0.508)
			(layers "F.Cu" "F.Mask" "F.Paste")
			(net "_NC_DDR0_32B_DQ3")
		)
		(pad "M6" smd circle
			(at -10.500004 -4.499991 180)
			(size 0.508 0.508)
			(layers "F.Cu" "F.Mask" "F.Paste")
			(net "_NC_DDR0_32B_A3")
		)
		(pad "M7" smd circle
			(at -9.500006 -4.499991 180)
			(size 0.508 0.508)
			(layers "F.Cu" "F.Mask" "F.Paste")
			(net "_NC_DDR0_32B_A5")
		)
		(pad "M8" smd circle
			(at -8.500008 -4.499991 180)
			(size 0.508 0.508)
			(layers "F.Cu" "F.Mask" "F.Paste")
			(net "_NC_DDR0_32B_BA0")
		)
		(pad "M9" smd circle
			(at -7.50001 -4.499991 180)
			(size 0.508 0.508)
			(layers "F.Cu" "F.Mask" "F.Paste")
			(net "_NC_DDR0_32B_CS0_L")
		)
		(pad "M10" smd circle
			(at -6.500012 -4.499991 180)
			(size 0.508 0.508)
			(layers "F.Cu" "F.Mask" "F.Paste")
			(net "_NC_NFP_DDR0_32B_PLL_ATO")
		)
		(pad "M11" smd circle
			(at -5.499989 -4.499991 180)
			(size 0.508 0.508)
			(layers "F.Cu" "F.Mask" "F.Paste")
			(net "GND")
		)
		(pad "M12" smd circle
			(at -4.499991 -4.499991 180)
			(size 0.508 0.508)
			(layers "F.Cu" "F.Mask" "F.Paste")
			(net "VDD_CORE")
		)
		(pad "M13" smd circle
			(at -3.499993 -4.499991 180)
			(size 0.508 0.508)
			(layers "F.Cu" "F.Mask" "F.Paste")
			(net "GND")
		)
		(pad "M14" smd circle
			(at -2.499995 -4.499991 180)
			(size 0.508 0.508)
			(layers "F.Cu" "F.Mask" "F.Paste")
			(net "VDD_CORE")
		)
		(pad "M15" smd circle
			(at -1.499997 -4.499991 180)
			(size 0.508 0.508)
			(layers "F.Cu" "F.Mask" "F.Paste")
			(net "GND")
		)
		(pad "M16" smd circle
			(at -0.499999 -4.499991 180)
			(size 0.508 0.508)
			(layers "F.Cu" "F.Mask" "F.Paste")
			(net "VDD_CORE")
		)
		(pad "M17" smd circle
			(at 0.499999 -4.499991 180)
			(size 0.508 0.508)
			(layers "F.Cu" "F.Mask" "F.Paste")
			(net "GND")
		)
		(pad "M18" smd circle
			(at 1.499997 -4.499991 180)
			(size 0.508 0.508)
			(layers "F.Cu" "F.Mask" "F.Paste")
			(net "VDD_CORE")
		)
		(pad "M19" smd circle
			(at 2.499995 -4.499991 180)
			(size 0.508 0.508)
			(layers "F.Cu" "F.Mask" "F.Paste")
			(net "GND")
		)
		(pad "M20" smd circle
			(at 3.499993 -4.499991 180)
			(size 0.508 0.508)
			(layers "F.Cu" "F.Mask" "F.Paste")
			(net "VDD_CORE")
		)
		(pad "M21" smd circle
			(at 4.499991 -4.499991 180)
			(size 0.508 0.508)
			(layers "F.Cu" "F.Mask" "F.Paste")
			(net "GND")
		)
		(pad "M22" smd circle
			(at 5.499989 -4.499991 180)
			(size 0.508 0.508)
			(layers "F.Cu" "F.Mask" "F.Paste")
			(net "VDD_CORE")
		)
		(pad "M23" smd circle
			(at 6.500012 -4.499991 180)
			(size 0.508 0.508)
			(layers "F.Cu" "F.Mask" "F.Paste")
			(net "GND")
		)
		(pad "M24" smd circle
			(at 7.50001 -4.499991 180)
			(size 0.508 0.508)
			(layers "F.Cu" "F.Mask" "F.Paste")
			(net "VDD_CORE")
		)
		(pad "M25" smd circle
			(at 8.500008 -4.499991 180)
			(size 0.508 0.508)
			(layers "F.Cu" "F.Mask" "F.Paste")
			(net "GND")
		)
		(pad "M26" smd circle
			(at 9.500006 -4.499991 180)
			(size 0.508 0.508)
			(layers "F.Cu" "F.Mask" "F.Paste")
			(net "VDD_CORE")
		)
		(pad "M27" smd circle
			(at 10.500004 -4.499991 180)
			(size 0.508 0.508)
			(layers "F.Cu" "F.Mask" "F.Paste")
			(net "VDDA_PLL")
		)
		(pad "M28" smd circle
			(at 11.500002 -4.499991 180)
			(size 0.508 0.508)
			(layers "F.Cu" "F.Mask" "F.Paste")
			(net "NFP_CLK_NRESET_L")
		)
		(pad "M29" smd circle
			(at 12.5 -4.499991 180)
			(size 0.508 0.508)
			(layers "F.Cu" "F.Mask" "F.Paste")
			(net "NFP_SRESET_L")
		)
		(pad "M30" smd circle
			(at 13.499998 -4.499991 180)
			(size 0.508 0.508)
			(layers "F.Cu" "F.Mask" "F.Paste")
			(net "VDD_CORE")
		)
		(pad "M31" smd circle
			(at 14.499996 -4.499991 180)
			(size 0.508 0.508)
			(layers "F.Cu" "F.Mask" "F.Paste")
			(net "NFP_CLK_NRESET_OUT_L")
		)
		(pad "M32" smd circle
			(at 15.499994 -4.499991 180)
			(size 0.508 0.508)
			(layers "F.Cu" "F.Mask" "F.Paste")
			(net "VDDA_TS0")
		)
		(pad "N1" smd circle
			(at -15.499994 -3.499993 180)
			(size 0.508 0.508)
			(layers "F.Cu" "F.Mask" "F.Paste")
			(net "_NC_DDR0_32B_DQ7")
		)
		(pad "N2" smd circle
			(at -14.499996 -3.499993 180)
			(size 0.508 0.508)
			(layers "F.Cu" "F.Mask" "F.Paste")
			(net "DDR_VDDQ")
		)
		(pad "N3" smd circle
			(at -13.499998 -3.499993 180)
			(size 0.508 0.508)
			(layers "F.Cu" "F.Mask" "F.Paste")
			(net "_NC_DDR0_32B_DQS0_P")
		)
		(pad "N4" smd circle
			(at -12.5 -3.499993 180)
			(size 0.508 0.508)
			(layers "F.Cu" "F.Mask" "F.Paste")
			(net "_NC_DDR0_32B_DQ6")
		)
		(pad "N5" smd circle
			(at -11.500002 -3.499993 180)
			(size 0.508 0.508)
			(layers "F.Cu" "F.Mask" "F.Paste")
			(net "DDR_VDDQ")
		)
		(pad "N6" smd circle
			(at -10.500004 -3.499993 180)
			(size 0.508 0.508)
			(layers "F.Cu" "F.Mask" "F.Paste")
			(net "_NC_DDR0_32B_A14")
		)
		(pad "N7" smd circle
			(at -9.500006 -3.499993 180)
			(size 0.508 0.508)
			(layers "F.Cu" "F.Mask" "F.Paste")
			(net "_NC_DDR0_32B_A7")
		)
		(pad "N8" smd circle
			(at -8.500008 -3.499993 180)
			(size 0.508 0.508)
			(layers "F.Cu" "F.Mask" "F.Paste")
			(net "DDR_VDDQ")
		)
		(pad "N9" smd circle
			(at -7.50001 -3.499993 180)
			(size 0.508 0.508)
			(layers "F.Cu" "F.Mask" "F.Paste")
			(net "_NC_DDR0_32A_PAR_OUT")
		)
		(pad "N10" smd circle
			(at -6.500012 -3.499993 180)
			(size 0.508 0.508)
			(layers "F.Cu" "F.Mask" "F.Paste")
			(net "A_DZQ0")
		)
		(pad "N11" smd circle
			(at -5.499989 -3.499993 180)
			(size 0.508 0.508)
			(layers "F.Cu" "F.Mask" "F.Paste")
			(net "VDD_CORE")
		)
		(pad "N12" smd circle
			(at -4.499991 -3.499993 180)
			(size 0.508 0.508)
			(layers "F.Cu" "F.Mask" "F.Paste")
			(net "GND")
		)
		(pad "N13" smd circle
			(at -3.499993 -3.499993 180)
			(size 0.508 0.508)
			(layers "F.Cu" "F.Mask" "F.Paste")
			(net "VDD_CORE")
		)
		(pad "N14" smd circle
			(at -2.499995 -3.499993 180)
			(size 0.508 0.508)
			(layers "F.Cu" "F.Mask" "F.Paste")
			(net "GND")
		)
		(pad "N15" smd circle
			(at -1.499997 -3.499993 180)
			(size 0.508 0.508)
			(layers "F.Cu" "F.Mask" "F.Paste")
			(net "VDD_CORE")
		)
		(pad "N16" smd circle
			(at -0.499999 -3.499993 180)
			(size 0.508 0.508)
			(layers "F.Cu" "F.Mask" "F.Paste")
			(net "GND")
		)
		(pad "N17" smd circle
			(at 0.499999 -3.499993 180)
			(size 0.508 0.508)
			(layers "F.Cu" "F.Mask" "F.Paste")
			(net "VDD_CORE")
		)
		(pad "N18" smd circle
			(at 1.499997 -3.499993 180)
			(size 0.508 0.508)
			(layers "F.Cu" "F.Mask" "F.Paste")
			(net "GND")
		)
		(pad "N19" smd circle
			(at 2.499995 -3.499993 180)
			(size 0.508 0.508)
			(layers "F.Cu" "F.Mask" "F.Paste")
			(net "VDD_CORE")
		)
		(pad "N20" smd circle
			(at 3.499993 -3.499993 180)
			(size 0.508 0.508)
			(layers "F.Cu" "F.Mask" "F.Paste")
			(net "GND")
		)
		(pad "N21" smd circle
			(at 4.499991 -3.499993 180)
			(size 0.508 0.508)
			(layers "F.Cu" "F.Mask" "F.Paste")
			(net "VDD_CORE")
		)
		(pad "N22" smd circle
			(at 5.499989 -3.499993 180)
			(size 0.508 0.508)
			(layers "F.Cu" "F.Mask" "F.Paste")
			(net "GND")
		)
		(pad "N23" smd circle
			(at 6.500012 -3.499993 180)
			(size 0.508 0.508)
			(layers "F.Cu" "F.Mask" "F.Paste")
			(net "VDD_CORE")
		)
		(pad "N24" smd circle
			(at 7.50001 -3.499993 180)
			(size 0.508 0.508)
			(layers "F.Cu" "F.Mask" "F.Paste")
			(net "GND")
		)
		(pad "N25" smd circle
			(at 8.500008 -3.499993 180)
			(size 0.508 0.508)
			(layers "F.Cu" "F.Mask" "F.Paste")
			(net "VDD_CORE")
		)
		(pad "N26" smd circle
			(at 9.500006 -3.499993 180)
			(size 0.508 0.508)
			(layers "F.Cu" "F.Mask" "F.Paste")
			(net "GND")
		)
		(pad "N27" smd circle
			(at 10.500004 -3.499993 180)
			(size 0.508 0.508)
			(layers "F.Cu" "F.Mask" "F.Paste")
			(net "VDDA_PLL")
		)
		(pad "N28" smd circle
			(at 11.500002 -3.499993 180)
			(size 0.508 0.508)
			(layers "F.Cu" "F.Mask" "F.Paste")
			(net "VDD_CORE_PGOOD")
		)
		(pad "N29" smd circle
			(at 12.5 -3.499993 180)
			(size 0.508 0.508)
			(layers "F.Cu" "F.Mask" "F.Paste")
			(net "GND")
		)
		(pad "N30" smd circle
			(at 13.499998 -3.499993 180)
			(size 0.508 0.508)
			(layers "F.Cu" "F.Mask" "F.Paste")
			(net "_NFP_PCIE0_RESET_OUT_L")
		)
		(pad "N31" smd circle
			(at 14.499996 -3.499993 180)
			(size 0.508 0.508)
			(layers "F.Cu" "F.Mask" "F.Paste")
			(net "NFP_UART_SR_RX")
		)
		(pad "N32" smd circle
			(at 15.499994 -3.499993 180)
			(size 0.508 0.508)
			(layers "F.Cu" "F.Mask" "F.Paste")
			(net "_NFP_UART_SR_TX")
		)
		(pad "P1" smd circle
			(at -15.499994 -2.499995 180)
			(size 0.508 0.508)
			(layers "F.Cu" "F.Mask" "F.Paste")
			(net "_NC_DDR0_32B_DM0")
		)
		(pad "P2" smd circle
			(at -14.499996 -2.499995 180)
			(size 0.508 0.508)
			(layers "F.Cu" "F.Mask" "F.Paste")
			(net "GND")
		)
		(pad "P3" smd circle
			(at -13.499998 -2.499995 180)
			(size 0.508 0.508)
			(layers "F.Cu" "F.Mask" "F.Paste")
			(net "_NC_DDR0_32B_DQS0_N")
		)
		(pad "P4" smd circle
			(at -12.5 -2.499995 180)
			(size 0.508 0.508)
			(layers "F.Cu" "F.Mask" "F.Paste")
			(net "_NC_DDR0_32B_DQ4")
		)
		(pad "P5" smd circle
			(at -11.500002 -2.499995 180)
			(size 0.508 0.508)
			(layers "F.Cu" "F.Mask" "F.Paste")
			(net "GND")
		)
		(pad "P6" smd circle
			(at -10.500004 -2.499995 180)
			(size 0.508 0.508)
			(layers "F.Cu" "F.Mask" "F.Paste")
			(net "_NC_DDR0_32B_DRAMRST_L")
		)
		(pad "P7" smd circle
			(at -9.500006 -2.499995 180)
			(size 0.508 0.508)
			(layers "F.Cu" "F.Mask" "F.Paste")
			(net "6N3961")
		)
		(pad "P8" smd circle
			(at -8.500008 -2.499995 180)
			(size 0.508 0.508)
			(layers "F.Cu" "F.Mask" "F.Paste")
			(net "GND")
		)
		(pad "P9" smd circle
			(at -7.50001 -2.499995 180)
			(size 0.508 0.508)
			(layers "F.Cu" "F.Mask" "F.Paste")
			(net "6N3963")
		)
		(pad "P10" smd circle
			(at -6.500012 -2.499995 180)
			(size 0.508 0.508)
			(layers "F.Cu" "F.Mask" "F.Paste")
			(net "_NC_NFP_DDR0_32A_PLL_DTO0")
		)
		(pad "P11" smd circle
			(at -5.499989 -2.499995 180)
			(size 0.508 0.508)
			(layers "F.Cu" "F.Mask" "F.Paste")
			(net "GND")
		)
		(pad "P12" smd circle
			(at -4.499991 -2.499995 180)
			(size 0.508 0.508)
			(layers "F.Cu" "F.Mask" "F.Paste")
			(net "VDD_CORE")
		)
		(pad "P13" smd circle
			(at -3.499993 -2.499995 180)
			(size 0.508 0.508)
			(layers "F.Cu" "F.Mask" "F.Paste")
			(net "GND")
		)
	)
)
